# S9S_MB_2U (Grand Teton) — schematic netlist excerpt (pin names and nets, part order shuffled) for the footprints in the layout excerpt that follows; sources: Cadence DE-HDL packaged netlist, KiCad conversion of 03242023_DA0F0TMBIJ0_F0T_Motherboard_J_brd_V01_OCP.brd

R1456  Q_RES  49.9 1% CHIP  pkg 0402LF  page 205 : A = FM_CPU_RMCA_CATERR_DLY_LVT3_R_N ; B = FM_CPU_RMCA_CATERR_DLY_N
R4029  Q_RES  1K 1% CHIP  pkg 0402LF  page 226 : A = PD_CPU0_ERRS_DIR ; B = GND

(kicad_pcb
	(version 20260206)
	(generator "pcbnew")
	(generator_version "10.0")
	(general
		(thickness 1.6)
		(legacy_teardrops no)
	)
	(paper "A4")
	(title_block
		(title "03242023_DA0F0TMBIJ0_F0T_Motherboard_J_brd_V01_OCP.brd")
		(comment 1 "Grand Teton / footprints 3101-3102 of 6105")
	)
	(layers
		(0 "F.Cu" signal "TOP")
		(4 "In1.Cu" signal "GND")
		(6 "In2.Cu" signal "IN1")
		(8 "In3.Cu" signal "GND1")
		(10 "In4.Cu" signal "IN2")
		(12 "In5.Cu" signal "GND2")
		(14 "In6.Cu" signal "IN3")
		(16 "In7.Cu" signal "GND3")
		(18 "In8.Cu" signal "VCC")
		(20 "In9.Cu" signal "VCC1")
		(22 "In10.Cu" signal "GND4")
		(24 "In11.Cu" signal "IN4")
		(26 "In12.Cu" signal "GND5")
		(28 "In13.Cu" signal "IN5")
		(30 "In14.Cu" signal "GND6")
		(32 "In15.Cu" signal "IN6")
		(34 "In16.Cu" signal "GND7")
		(2 "B.Cu" signal "BOTTOM")
		(9 "F.Adhes" user "F.Adhesive")
		(11 "B.Adhes" user "B.Adhesive")
		(13 "F.Paste" user "Package Geometry/Pastemask Top")
		(15 "B.Paste" user "Package Geometry/Pastemask Bottom")
		(5 "F.SilkS" user "Ref Des/Silkscreen Top")
		(7 "B.SilkS" user "Ref Des/Silkscreen Bottom")
		(1 "F.Mask" user "Board Geometry/Soldermask Top")
		(3 "B.Mask" user "Board Geometry/Soldermask Bottom")
		(17 "Dwgs.User" user "User.Drawings")
		(19 "Cmts.User" user "User.Comments")
		(21 "Eco1.User" user "User.Eco1")
		(23 "Eco2.User" user "User.Eco2")
		(25 "Edge.Cuts" user "Board Geometry/Outline")
		(27 "Margin" user)
		(31 "F.CrtYd" user "Package Geometry/Place Bound Top")
		(29 "B.CrtYd" user "Package Geometry/Place Bound Bottom")
		(35 "F.Fab" user "Ref Des/Assembly Top")
		(33 "B.Fab" user "Ref Des/Assembly Bottom")
	)
	(footprint ""
		(layer "F.Cu")
		(at 117.53088 -101.793548 90)
		(property "Reference" "R4029"
			(at 0 0 90)
			(layer "F.SilkS")
			(hide yes)
			(effects
				(font
					(size 1.27 1.27)
				)
			)
		)
		(property "Value" ""
			(at 0 0 90)
			(layer "F.Fab")
			(effects
				(font
					(size 1.27 1.27)
				)
			)
		)
		(duplicate_pad_numbers_are_jumpers no)
		(fp_line
			(start 0.7874 -0.4064)
			(end 0.7874 0.4064)
			(stroke
				(width 0.1524)
				(type default)
			)
			(layer "F.SilkS")
		)
		(fp_line
			(start -0.7874 -0.4064)
			(end 0.7874 -0.4064)
			(stroke
				(width 0.1524)
				(type default)
			)
			(layer "F.SilkS")
		)
		(fp_line
			(start 0.7874 0.4064)
			(end -0.7874 0.4064)
			(stroke
				(width 0.1524)
				(type default)
			)
			(layer "F.SilkS")
		)
		(fp_line
			(start -0.7874 0.4064)
			(end -0.7874 -0.4064)
			(stroke
				(width 0.1524)
				(type default)
			)
			(layer "F.SilkS")
		)
		(fp_line
			(start -0.12065 -0.305054)
			(end -0.12065 -0.2794)
			(stroke
				(width 0.1)
				(type default)
			)
			(layer "F.Fab")
		)
		(fp_line
			(start -0.67945 -0.305054)
			(end -0.12065 -0.305054)
			(stroke
				(width 0.1)
				(type default)
			)
			(layer "F.Fab")
		)
		(fp_line
			(start 0.67945 -0.3048)
			(end 0.67945 0.3048)
			(stroke
				(width 0.1)
				(type default)
			)
			(layer "F.Fab")
		)
		(fp_line
			(start 0.12065 -0.3048)
			(end 0.67945 -0.3048)
			(stroke
				(width 0.1)
				(type default)
			)
			(layer "F.Fab")
		)
		(fp_line
			(start 0.12065 -0.2794)
			(end 0.12065 -0.3048)
			(stroke
				(width 0.1)
				(type default)
			)
			(layer "F.Fab")
		)
		(fp_line
			(start -0.12065 -0.2794)
			(end 0.12065 -0.2794)
			(stroke
				(width 0.1)
				(type default)
			)
			(layer "F.Fab")
		)
		(fp_line
			(start 0.120396 0.2794)
			(end -0.12065 0.2794)
			(stroke
				(width 0.1)
				(type default)
			)
			(layer "F.Fab")
		)
		(fp_line
			(start -0.12065 0.2794)
			(end -0.12065 0.3048)
			(stroke
				(width 0.1)
				(type default)
			)
			(layer "F.Fab")
		)
		(fp_line
			(start 0.67945 0.3048)
			(end 0.120396 0.3048)
			(stroke
				(width 0.1)
				(type default)
			)
			(layer "F.Fab")
		)
		(fp_line
			(start 0.120396 0.3048)
			(end 0.120396 0.2794)
			(stroke
				(width 0.1)
				(type default)
			)
			(layer "F.Fab")
		)
		(fp_line
			(start -0.12065 0.3048)
			(end -0.67945 0.3048)
			(stroke
				(width 0.1)
				(type default)
			)
			(layer "F.Fab")
		)
		(fp_line
			(start -0.67945 0.3048)
			(end -0.67945 -0.305054)
			(stroke
				(width 0.1)
				(type default)
			)
			(layer "F.Fab")
		)
		(pad "1" smd circle
			(at -0.40005 0 90)
			(size 0 0)
			(layers "F.Cu" "F.Mask" "F.Paste")
			(net "PD_CPU0_ERRS_DIR")
		)
		(pad "2" smd circle
			(at 0.40005 0 90)
			(size 0 0)
			(layers "F.Cu" "F.Mask" "F.Paste")
			(net "GND")
		)
	)
	(footprint ""
		(layer "F.Cu")
		(at 309.522622 -47.107348)
		(property "Reference" "R1456"
			(at 0 0 0)
			(layer "F.SilkS")
			(hide yes)
			(effects
				(font
					(size 1.27 1.27)
				)
			)
		)
		(property "Value" ""
			(at 0 0 0)
			(layer "F.Fab")
			(effects
				(font
					(size 1.27 1.27)
				)
			)
		)
		(duplicate_pad_numbers_are_jumpers no)
		(fp_line
			(start -0.7874 -0.4064)
			(end 0.7874 -0.4064)
			(stroke
				(width 0.1524)
				(type default)
			)
			(layer "F.SilkS")
		)
		(fp_line
			(start -0.7874 0.4064)
			(end -0.7874 -0.4064)
			(stroke
				(width 0.1524)
				(type default)
			)
			(layer "F.SilkS")
		)
		(fp_line
			(start 0.7874 -0.4064)
			(end 0.7874 0.4064)
			(stroke
				(width 0.1524)
				(type default)
			)
			(layer "F.SilkS")
		)
		(fp_line
			(start 0.7874 0.4064)
			(end -0.7874 0.4064)
			(stroke
				(width 0.1524)
				(type default)
			)
			(layer "F.SilkS")
		)
		(fp_line
			(start -0.67945 -0.305054)
			(end -0.12065 -0.305054)
			(stroke
				(width 0.1)
				(type default)
			)
			(layer "F.Fab")
		)
		(fp_line
			(start -0.67945 0.3048)
			(end -0.67945 -0.305054)
			(stroke
				(width 0.1)
				(type default)
			)
			(layer "F.Fab")
		)
		(fp_line
			(start -0.12065 -0.305054)
			(end -0.12065 -0.2794)
			(stroke
				(width 0.1)
				(type default)
			)
			(layer "F.Fab")
		)
		(fp_line
			(start -0.12065 -0.2794)
			(end 0.12065 -0.2794)
			(stroke
				(width 0.1)
				(type default)
			)
			(layer "F.Fab")
		)
		(fp_line
			(start -0.12065 0.2794)
			(end -0.12065 0.3048)
			(stroke
				(width 0.1)
				(type default)
			)
			(layer "F.Fab")
		)
		(fp_line
			(start -0.12065 0.3048)
			(end -0.67945 0.3048)
			(stroke
				(width 0.1)
				(type default)
			)
			(layer "F.Fab")
		)
		(fp_line
			(start 0.120396 0.2794)
			(end -0.12065 0.2794)
			(stroke
				(width 0.1)
				(type default)
			)
			(layer "F.Fab")
		)
		(fp_line
			(start 0.120396 0.3048)
			(end 0.120396 0.2794)
			(stroke
				(width 0.1)
				(type default)
			)
			(layer "F.Fab")
		)
		(fp_line
			(start 0.12065 -0.3048)
			(end 0.67945 -0.3048)
			(stroke
				(width 0.1)
				(type default)
			)
			(layer "F.Fab")
		)
		(fp_line
			(start 0.12065 -0.2794)
			(end 0.12065 -0.3048)
			(stroke
				(width 0.1)
				(type default)
			)
			(layer "F.Fab")
		)
		(fp_line
			(start 0.67945 -0.3048)
			(end 0.67945 0.3048)
			(stroke
				(width 0.1)
				(type default)
			)
			(layer "F.Fab")
		)
		(fp_line
			(start 0.67945 0.3048)
			(end 0.120396 0.3048)
			(stroke
				(width 0.1)
				(type default)
			)
			(layer "F.Fab")
		)
		(pad "1" smd circle
			(at -0.40005 0)
			(size 0 0)
			(layers "F.Cu" "F.Mask" "F.Paste")
			(net "FM_CPU_RMCA_CATERR_DLY_LVT3_R_N")
		)
		(pad "2" smd circle
			(at 0.40005 0)
			(size 0 0)
			(layers "F.Cu" "F.Mask" "F.Paste")
			(net "FM_CPU_RMCA_CATERR_DLY_N")
		)
	)
)
